# BASEBOARD_FAB2 (Tioga Pass) — schematic netlist excerpt (pin names and nets, part order shuffled) for the footprints in the layout excerpt that follows; sources: Cadence DE-HDL packaged netlist, KiCad conversion of Wiwynn_Tioga_Pass_MB.brd

C4C19  CAP_A  0.1UF 16V 10% X7R  pkg 0402V  page 204 : A = VR_FET_SW_P12V_STBY_PVCCIN_CPU0 ; B = GND
C2D31  CAP_A  22.0UF 4V 20% X6S  pkg 0603V  page 76 : A = PVCCIN_CPU1 ; B = GND
R25W25  120R2F-GP  1%  pkg RCL_GP  page 151 : \1\ = GND ; \2\ = BMC_M_A13

(kicad_pcb
	(version 20260206)
	(generator "pcbnew")
	(generator_version "10.0")
	(general
		(thickness 1.6)
		(legacy_teardrops no)
	)
	(paper "A4")
	(title_block
		(title "Wiwynn_Tioga_Pass_MB.brd")
		(comment 1 "Tioga Pass / footprints 953-955 of 4770")
	)
	(layers
		(0 "F.Cu" signal "TOP")
		(4 "In1.Cu" signal "L2GND")
		(6 "In2.Cu" signal "L3")
		(8 "In3.Cu" signal "L4GND")
		(10 "In4.Cu" signal "L5")
		(12 "In5.Cu" signal "L6GND")
		(14 "In6.Cu" signal "L7VCC")
		(16 "In7.Cu" signal "L8VCC")
		(18 "In8.Cu" signal "L9GND")
		(20 "In9.Cu" signal "L10")
		(22 "In10.Cu" signal "L11GND")
		(24 "In11.Cu" signal "L12")
		(26 "In12.Cu" signal "L13GND")
		(2 "B.Cu" signal "BOTTOM")
		(9 "F.Adhes" user "F.Adhesive")
		(11 "B.Adhes" user "B.Adhesive")
		(13 "F.Paste" user "Package Geometry/Pastemask Top")
		(15 "B.Paste" user "Package Geometry/Pastemask Bottom")
		(5 "F.SilkS" user "Ref Des/Silkscreen Top")
		(7 "B.SilkS" user "Ref Des/Silkscreen Bottom")
		(1 "F.Mask" user "Board Geometry/Soldermask Top")
		(3 "B.Mask" user "Board Geometry/Soldermask Bottom")
		(17 "Dwgs.User" user "User.Drawings")
		(19 "Cmts.User" user "User.Comments")
		(21 "Eco1.User" user "User.Eco1")
		(23 "Eco2.User" user "User.Eco2")
		(25 "Edge.Cuts" user "Board Geometry/Outline")
		(27 "Margin" user)
		(31 "F.CrtYd" user "Package Geometry/Place Bound Top")
		(29 "B.CrtYd" user "Package Geometry/Place Bound Bottom")
		(35 "F.Fab" user "Ref Des/Assembly Top")
		(33 "B.Fab" user "Ref Des/Assembly Bottom")
	)
	(footprint ""
		(layer "F.Cu")
		(at 198.042276 -92.967048 90)
		(property "Reference" "C4C19"
			(at 0 0 90)
			(layer "F.SilkS")
			(hide yes)
			(effects
				(font
					(size 1.27 1.27)
				)
			)
		)
		(property "Value" ""
			(at 0 0 90)
			(layer "F.Fab")
			(effects
				(font
					(size 1.27 1.27)
				)
			)
		)
		(duplicate_pad_numbers_are_jumpers no)
		(fp_rect
			(start 0.3048 0.9906)
			(end -0.3048 -0.1016)
			(stroke
				(width 0)
				(type default)
			)
			(fill no)
			(layer "F.CrtYd")
		)
		(fp_line
			(start 0.3048 -0.1016)
			(end -0.3048 -0.1016)
			(stroke
				(width 0.1)
				(type default)
			)
			(layer "F.Fab")
		)
		(fp_line
			(start -0.3048 -0.1016)
			(end -0.3048 0.9906)
			(stroke
				(width 0.1)
				(type default)
			)
			(layer "F.Fab")
		)
		(fp_line
			(start 0.3048 0.9906)
			(end 0.3048 -0.1016)
			(stroke
				(width 0.1)
				(type default)
			)
			(layer "F.Fab")
		)
		(fp_line
			(start -0.3048 0.9906)
			(end 0.3048 0.9906)
			(stroke
				(width 0.1)
				(type default)
			)
			(layer "F.Fab")
		)
		(pad "1" smd rect
			(at 0 0 90)
			(size 0.508 0.508)
			(layers "F.Cu" "F.Mask" "F.Paste")
			(net "VR_FET_SW_P12V_STBY_PVCCIN_CPU0")
		)
		(pad "2" smd rect
			(at 0 0.889 90)
			(size 0.508 0.508)
			(layers "F.Cu" "F.Mask" "F.Paste")
			(net "GND")
		)
		(zone
			(layer "F.Cu")
			(hatch none 0.5)
			(connect_pads
				(clearance 0)
			)
			(min_thickness 0.25)
			(keepout
				(tracks allowed)
				(vias not_allowed)
				(pads allowed)
				(copperpour not_allowed)
				(footprints allowed)
			)
			(placement
				(enabled no)
				(sheetname "")
			)
			(fill
				(thermal_gap 0.5)
				(thermal_bridge_width 0.5)
				(island_removal_mode 0)
			)
			(polygon
				(pts
					(xy 198.677276 -93.221048) (xy 198.296276 -93.221048) (xy 198.296276 -92.713048) (xy 198.677276 -92.713048)
				)
			)
		)
		(zone
			(layer "F.Cu")
			(hatch none 0.5)
			(connect_pads
				(clearance 0)
			)
			(min_thickness 0.25)
			(keepout
				(tracks not_allowed)
				(vias allowed)
				(pads allowed)
				(copperpour not_allowed)
				(footprints allowed)
			)
			(placement
				(enabled no)
				(sheetname "")
			)
			(fill
				(thermal_gap 0.5)
				(thermal_bridge_width 0.5)
				(island_removal_mode 0)
			)
			(polygon
				(pts
					(xy 198.677276 -93.221048) (xy 198.296276 -93.221048) (xy 198.296276 -92.713048) (xy 198.677276 -92.713048)
				)
			)
		)
	)
	(footprint ""
		(layer "F.Cu")
		(at 94.45244 -73.318116)
		(property "Reference" "C2D31"
			(at 0 0 0)
			(layer "F.SilkS")
			(hide yes)
			(effects
				(font
					(size 1.27 1.27)
				)
			)
		)
		(property "Value" ""
			(at 0 0 0)
			(layer "F.Fab")
			(effects
				(font
					(size 1.27 1.27)
				)
			)
		)
		(duplicate_pad_numbers_are_jumpers no)
		(fp_poly
			(pts
				(xy -0.4953 -0.2032) (xy 0.4953 -0.2032) (xy 0.4953 1.6002) (xy -0.4953 1.6002)
			)
			(stroke
				(width 0)
				(type default)
			)
			(fill no)
			(layer "F.CrtYd")
		)
		(fp_line
			(start -0.4953 -0.2032)
			(end 0.4953 -0.2032)
			(stroke
				(width 0.1)
				(type default)
			)
			(layer "F.Fab")
		)
		(fp_line
			(start -0.4953 1.6002)
			(end -0.4953 -0.2032)
			(stroke
				(width 0.1)
				(type default)
			)
			(layer "F.Fab")
		)
		(fp_line
			(start 0.4953 -0.2032)
			(end 0.4953 1.6002)
			(stroke
				(width 0.1)
				(type default)
			)
			(layer "F.Fab")
		)
		(fp_line
			(start 0.4953 1.6002)
			(end -0.4953 1.6002)
			(stroke
				(width 0.1)
				(type default)
			)
			(layer "F.Fab")
		)
		(pad "1" smd rect
			(at 0 0)
			(size 0.762 0.889)
			(layers "F.Cu" "F.Mask" "F.Paste")
			(net "PVCCIN_CPU1")
		)
		(pad "2" smd rect
			(at 0 1.397)
			(size 0.762 0.889)
			(layers "F.Cu" "F.Mask" "F.Paste")
			(net "GND")
		)
		(zone
			(layer "F.Cu")
			(hatch none 0.5)
			(connect_pads
				(clearance 0)
			)
			(min_thickness 0.25)
			(keepout
				(tracks not_allowed)
				(vias allowed)
				(pads allowed)
				(copperpour not_allowed)
				(footprints allowed)
			)
			(placement
				(enabled no)
				(sheetname "")
			)
			(fill
				(thermal_gap 0.5)
				(thermal_bridge_width 0.5)
				(island_removal_mode 0)
			)
			(polygon
				(pts
					(xy 94.07144 -72.873616) (xy 94.83344 -72.873616) (xy 94.83344 -72.365616) (xy 94.07144 -72.365616)
				)
			)
		)
	)
	(footprint ""
		(layer "F.Cu")
		(at 437.690006 -41.663874 180)
		(property "Reference" "R25W25"
			(at 0 0 180)
			(layer "F.SilkS")
			(hide yes)
			(effects
				(font
					(size 1.27 1.27)
				)
			)
		)
		(property "Value" "*"
			(at 0.064008 -4.108196 180)
			(unlocked yes)
			(layer "F.Fab")
			(hide yes)
			(effects
				(font
					(size 1.27 1.016)
					(thickness 0.1524)
				)
			)
		)
		(property "Device Type" "120R2F-GP_RCL_GP-120R2F-GP,64.A"
			(at 0.064008 -5.632196 180)
			(unlocked yes)
			(layer "F.Fab")
			(hide yes)
			(effects
				(font
					(size 1.27 1.016)
					(thickness 0.1524)
				)
			)
		)
		(duplicate_pad_numbers_are_jumpers no)
		(fp_line
			(start 0.508 -0.9398)
			(end -0.508 -0.9398)
			(stroke
				(width 0.1524)
				(type default)
			)
			(layer "F.SilkS")
		)
		(fp_line
			(start -0.508 -0.9398)
			(end -0.508 0.9398)
			(stroke
				(width 0.1524)
				(type default)
			)
			(layer "F.SilkS")
		)
		(fp_rect
			(start -0.508 0.9398)
			(end 0.508 -0.9398)
			(stroke
				(width 0)
				(type default)
			)
			(fill no)
			(layer "F.CrtYd")
		)
		(fp_rect
			(start -0.508 0.9398)
			(end 0.508 -0.9398)
			(stroke
				(width 0)
				(type default)
			)
			(fill no)
			(layer "F.Fab")
		)
		(pad "1" smd custom
			(at 0 -0.4445 180)
			(size 0.1397 0.1397)
			(layers "F.Cu" "F.Mask" "F.Paste")
			(net "GND")
			(options
				(clearance outline)
				(anchor circle)
			)
			(primitives
				(gr_poly
					(pts
						(arc
							(start -0.1778 -0.2794)
							(mid -0.249642 -0.249642)
							(end -0.2794 -0.1778)
						)
						(arc
							(start -0.2794 0.1778)
							(mid -0.249642 0.249642)
							(end -0.1778 0.2794)
						)
						(arc
							(start 0.1778 0.2794)
							(mid 0.249642 0.249642)
							(end 0.2794 0.1778)
						)
						(arc
							(start 0.2794 -0.1778)
							(mid 0.249642 -0.249642)
							(end 0.1778 -0.2794)
						)
					)
					(width 0)
					(fill yes)
				)
			)
		)
		(pad "2" smd custom
			(at 0 0.4445 180)
			(size 0.1397 0.1397)
			(layers "F.Cu" "F.Mask" "F.Paste")
			(net "BMC_M_A13")
			(options
				(clearance outline)
				(anchor circle)
			)
			(primitives
				(gr_poly
					(pts
						(arc
							(start -0.1778 -0.2794)
							(mid -0.249642 -0.249642)
							(end -0.2794 -0.1778)
						)
						(arc
							(start -0.2794 0.1778)
							(mid -0.249642 0.249642)
							(end -0.1778 0.2794)
						)
						(arc
							(start 0.1778 0.2794)
							(mid 0.249642 0.249642)
							(end 0.2794 0.1778)
						)
						(arc
							(start 0.2794 -0.1778)
							(mid 0.249642 -0.249642)
							(end 0.1778 -0.2794)
						)
					)
					(width 0)
					(fill yes)
				)
			)
		)
	)
)
